# SCM (Grand Teton) — schematic netlist excerpt (pin names and nets, part order shuffled) for the footprints in the layout excerpt that follows; sources: Cadence DE-HDL packaged netlist, KiCad conversion of 12092022_DA0F0TMDCD0_F0T_Management_Board_D_brd_V3_OCP.brd

R758  Q_RES  4.7K 1% CHIP  pkg 0402LF  page 30 : A = P3V3_RGM ; B = UART_BMC_5_RXD_R
R886  Q_RES  4.7K 1% CHIP  pkg 0402LF  page 35 : A = P3V3_AUX ; B = PWRGD_P5V_AUX_R1

(kicad_pcb
	(version 20260206)
	(generator "pcbnew")
	(generator_version "10.0")
	(general
		(thickness 1.6)
		(legacy_teardrops no)
	)
	(paper "A4")
	(title_block
		(title "12092022_DA0F0TMDCD0_F0T_Management_Board_D_brd_V3_OCP.brd")
		(comment 1 "Grand Teton / footprints 237-238 of 1440")
	)
	(layers
		(0 "F.Cu" signal "TOP")
		(4 "In1.Cu" signal "GND")
		(6 "In2.Cu" signal "IN1")
		(8 "In3.Cu" signal "GND1")
		(10 "In4.Cu" signal "IN2")
		(12 "In5.Cu" signal "VCC")
		(14 "In6.Cu" signal "VCC1")
		(16 "In7.Cu" signal "IN3")
		(18 "In8.Cu" signal "GND2")
		(20 "In9.Cu" signal "IN4")
		(22 "In10.Cu" signal "GND3")
		(2 "B.Cu" signal "BOTTOM")
		(9 "F.Adhes" user "F.Adhesive")
		(11 "B.Adhes" user "B.Adhesive")
		(13 "F.Paste" user "Package Geometry/Pastemask Top")
		(15 "B.Paste" user "Package Geometry/Pastemask Bottom")
		(5 "F.SilkS" user "Ref Des/Silkscreen Top")
		(7 "B.SilkS" user "Ref Des/Silkscreen Bottom")
		(1 "F.Mask" user "Board Geometry/Soldermask Top")
		(3 "B.Mask" user "Board Geometry/Soldermask Bottom")
		(17 "Dwgs.User" user "User.Drawings")
		(19 "Cmts.User" user "User.Comments")
		(21 "Eco1.User" user "User.Eco1")
		(23 "Eco2.User" user "User.Eco2")
		(25 "Edge.Cuts" user "Board Geometry/Outline")
		(27 "Margin" user)
		(31 "F.CrtYd" user "Package Geometry/Place Bound Top")
		(29 "B.CrtYd" user "Package Geometry/Place Bound Bottom")
		(35 "F.Fab" user "Ref Des/Assembly Top")
		(33 "B.Fab" user "Ref Des/Assembly Bottom")
	)
	(footprint ""
		(layer "F.Cu")
		(at 33.3248 -66.5226 180)
		(property "Reference" "R758"
			(at 0 0 180)
			(layer "F.SilkS")
			(hide yes)
			(effects
				(font
					(size 1.27 1.27)
				)
			)
		)
		(property "Value" ""
			(at 0 0 180)
			(layer "F.Fab")
			(effects
				(font
					(size 1.27 1.27)
				)
			)
		)
		(duplicate_pad_numbers_are_jumpers no)
		(fp_line
			(start 0.7874 0.4064)
			(end -0.7874 0.4064)
			(stroke
				(width 0.1524)
				(type default)
			)
			(layer "F.SilkS")
		)
		(fp_line
			(start 0.7874 -0.4064)
			(end 0.7874 0.4064)
			(stroke
				(width 0.1524)
				(type default)
			)
			(layer "F.SilkS")
		)
		(fp_line
			(start -0.7874 0.4064)
			(end -0.7874 -0.4064)
			(stroke
				(width 0.1524)
				(type default)
			)
			(layer "F.SilkS")
		)
		(fp_line
			(start -0.7874 -0.4064)
			(end 0.7874 -0.4064)
			(stroke
				(width 0.1524)
				(type default)
			)
			(layer "F.SilkS")
		)
		(fp_line
			(start 0.67945 0.3048)
			(end 0.120396 0.3048)
			(stroke
				(width 0.1)
				(type default)
			)
			(layer "F.Fab")
		)
		(fp_line
			(start 0.67945 -0.3048)
			(end 0.67945 0.3048)
			(stroke
				(width 0.1)
				(type default)
			)
			(layer "F.Fab")
		)
		(fp_line
			(start 0.12065 -0.2794)
			(end 0.12065 -0.3048)
			(stroke
				(width 0.1)
				(type default)
			)
			(layer "F.Fab")
		)
		(fp_line
			(start 0.12065 -0.3048)
			(end 0.67945 -0.3048)
			(stroke
				(width 0.1)
				(type default)
			)
			(layer "F.Fab")
		)
		(fp_line
			(start 0.120396 0.3048)
			(end 0.120396 0.2794)
			(stroke
				(width 0.1)
				(type default)
			)
			(layer "F.Fab")
		)
		(fp_line
			(start 0.120396 0.2794)
			(end -0.12065 0.2794)
			(stroke
				(width 0.1)
				(type default)
			)
			(layer "F.Fab")
		)
		(fp_line
			(start -0.12065 0.3048)
			(end -0.67945 0.3048)
			(stroke
				(width 0.1)
				(type default)
			)
			(layer "F.Fab")
		)
		(fp_line
			(start -0.12065 0.2794)
			(end -0.12065 0.3048)
			(stroke
				(width 0.1)
				(type default)
			)
			(layer "F.Fab")
		)
		(fp_line
			(start -0.12065 -0.2794)
			(end 0.12065 -0.2794)
			(stroke
				(width 0.1)
				(type default)
			)
			(layer "F.Fab")
		)
		(fp_line
			(start -0.12065 -0.305054)
			(end -0.12065 -0.2794)
			(stroke
				(width 0.1)
				(type default)
			)
			(layer "F.Fab")
		)
		(fp_line
			(start -0.67945 0.3048)
			(end -0.67945 -0.305054)
			(stroke
				(width 0.1)
				(type default)
			)
			(layer "F.Fab")
		)
		(fp_line
			(start -0.67945 -0.305054)
			(end -0.12065 -0.305054)
			(stroke
				(width 0.1)
				(type default)
			)
			(layer "F.Fab")
		)
		(pad "1" smd circle
			(at -0.40005 0 180)
			(size 0 0)
			(layers "F.Cu" "F.Mask" "F.Paste")
			(net "P3V3_RGM")
		)
		(pad "2" smd circle
			(at 0.40005 0 180)
			(size 0 0)
			(layers "F.Cu" "F.Mask" "F.Paste")
			(net "UART_BMC_5_RXD_R")
		)
	)
	(footprint ""
		(layer "F.Cu")
		(at 12.319 -98.4758)
		(property "Reference" "R886"
			(at 0 0 0)
			(layer "F.SilkS")
			(hide yes)
			(effects
				(font
					(size 1.27 1.27)
				)
			)
		)
		(property "Value" ""
			(at 0 0 0)
			(layer "F.Fab")
			(effects
				(font
					(size 1.27 1.27)
				)
			)
		)
		(duplicate_pad_numbers_are_jumpers no)
		(fp_line
			(start -0.7874 -0.4064)
			(end 0.7874 -0.4064)
			(stroke
				(width 0.1524)
				(type default)
			)
			(layer "F.SilkS")
		)
		(fp_line
			(start -0.7874 0.4064)
			(end -0.7874 -0.4064)
			(stroke
				(width 0.1524)
				(type default)
			)
			(layer "F.SilkS")
		)
		(fp_line
			(start 0.7874 -0.4064)
			(end 0.7874 0.4064)
			(stroke
				(width 0.1524)
				(type default)
			)
			(layer "F.SilkS")
		)
		(fp_line
			(start 0.7874 0.4064)
			(end -0.7874 0.4064)
			(stroke
				(width 0.1524)
				(type default)
			)
			(layer "F.SilkS")
		)
		(fp_line
			(start -0.67945 -0.305054)
			(end -0.12065 -0.305054)
			(stroke
				(width 0.1)
				(type default)
			)
			(layer "F.Fab")
		)
		(fp_line
			(start -0.67945 0.3048)
			(end -0.67945 -0.305054)
			(stroke
				(width 0.1)
				(type default)
			)
			(layer "F.Fab")
		)
		(fp_line
			(start -0.12065 -0.305054)
			(end -0.12065 -0.2794)
			(stroke
				(width 0.1)
				(type default)
			)
			(layer "F.Fab")
		)
		(fp_line
			(start -0.12065 -0.2794)
			(end 0.12065 -0.2794)
			(stroke
				(width 0.1)
				(type default)
			)
			(layer "F.Fab")
		)
		(fp_line
			(start -0.12065 0.2794)
			(end -0.12065 0.3048)
			(stroke
				(width 0.1)
				(type default)
			)
			(layer "F.Fab")
		)
		(fp_line
			(start -0.12065 0.3048)
			(end -0.67945 0.3048)
			(stroke
				(width 0.1)
				(type default)
			)
			(layer "F.Fab")
		)
		(fp_line
			(start 0.120396 0.2794)
			(end -0.12065 0.2794)
			(stroke
				(width 0.1)
				(type default)
			)
			(layer "F.Fab")
		)
		(fp_line
			(start 0.120396 0.3048)
			(end 0.120396 0.2794)
			(stroke
				(width 0.1)
				(type default)
			)
			(layer "F.Fab")
		)
		(fp_line
			(start 0.12065 -0.3048)
			(end 0.67945 -0.3048)
			(stroke
				(width 0.1)
				(type default)
			)
			(layer "F.Fab")
		)
		(fp_line
			(start 0.12065 -0.2794)
			(end 0.12065 -0.3048)
			(stroke
				(width 0.1)
				(type default)
			)
			(layer "F.Fab")
		)
		(fp_line
			(start 0.67945 -0.3048)
			(end 0.67945 0.3048)
			(stroke
				(width 0.1)
				(type default)
			)
			(layer "F.Fab")
		)
		(fp_line
			(start 0.67945 0.3048)
			(end 0.120396 0.3048)
			(stroke
				(width 0.1)
				(type default)
			)
			(layer "F.Fab")
		)
		(pad "1" smd circle
			(at -0.40005 0)
			(size 0 0)
			(layers "F.Cu" "F.Mask" "F.Paste")
			(net "P3V3_AUX")
		)
		(pad "2" smd circle
			(at 0.40005 0)
			(size 0 0)
			(layers "F.Cu" "F.Mask" "F.Paste")
			(net "PWRGD_P5V_AUX_R1")
		)
	)
)
